# T6G (Grand Teton) — schematic netlist excerpt (pin names and nets, part order shuffled) for the footprints in the layout excerpt that follows; sources: Cadence DE-HDL packaged netlist, KiCad conversion of 04192023_DAF0TMB3IC0_F0TG_MB_C_brd_V02_OCP.brd

R510  Q_RES  15 1% CHIP  pkg 0402LF  page 47 : A = M_K_CPU1_ALERT_N ; B = M_K_CPU1_ALERT_R_N
C2366  Q_CAP  22UF 4V 20% X6S  pkg C0402  page 73 : A = PVDDCR_CPU1_P1 ; B = GND

(kicad_pcb
	(version 20260206)
	(generator "pcbnew")
	(generator_version "10.0")
	(general
		(thickness 1.6)
		(legacy_teardrops no)
	)
	(paper "A4")
	(title_block
		(title "04192023_DAF0TMB3IC0_F0TG_MB_C_brd_V02_OCP.brd")
		(comment 1 "Grand Teton / footprints 7386-7387 of 8354")
	)
	(layers
		(0 "F.Cu" signal "TOP")
		(4 "In1.Cu" signal "GND")
		(6 "In2.Cu" signal "IN1")
		(8 "In3.Cu" signal "GND1")
		(10 "In4.Cu" signal "IN2")
		(12 "In5.Cu" signal "GND2")
		(14 "In6.Cu" signal "IN3")
		(16 "In7.Cu" signal "GND3")
		(18 "In8.Cu" signal "VCC")
		(20 "In9.Cu" signal "VCC1")
		(22 "In10.Cu" signal "GND4")
		(24 "In11.Cu" signal "IN4")
		(26 "In12.Cu" signal "GND5")
		(28 "In13.Cu" signal "IN5")
		(30 "In14.Cu" signal "GND6")
		(32 "In15.Cu" signal "IN6")
		(34 "In16.Cu" signal "GND7")
		(2 "B.Cu" signal "BOTTOM")
		(9 "F.Adhes" user "F.Adhesive")
		(11 "B.Adhes" user "B.Adhesive")
		(13 "F.Paste" user "Package Geometry/Pastemask Top")
		(15 "B.Paste" user "Package Geometry/Pastemask Bottom")
		(5 "F.SilkS" user "Ref Des/Silkscreen Top")
		(7 "B.SilkS" user "Ref Des/Silkscreen Bottom")
		(1 "F.Mask" user "Board Geometry/Soldermask Top")
		(3 "B.Mask" user "Board Geometry/Soldermask Bottom")
		(17 "Dwgs.User" user "User.Drawings")
		(19 "Cmts.User" user "User.Comments")
		(21 "Eco1.User" user "User.Eco1")
		(23 "Eco2.User" user "User.Eco2")
		(25 "Edge.Cuts" user "Board Geometry/Outline")
		(27 "Margin" user)
		(31 "F.CrtYd" user "Package Geometry/Place Bound Top")
		(29 "B.CrtYd" user "Package Geometry/Place Bound Bottom")
		(35 "F.Fab" user "Ref Des/Assembly Top")
		(33 "B.Fab" user "Ref Des/Assembly Bottom")
	)
	(footprint ""
		(layer "B.Cu")
		(at 102.275386 -268.418564)
		(property "Reference" "C2366"
			(at 0 0 0)
			(layer "B.SilkS")
			(hide yes)
			(effects
				(font
					(size 1.27 1.27)
				)
				(justify mirror)
			)
		)
		(property "Value" ""
			(at 0 0 0)
			(layer "B.Fab")
			(effects
				(font
					(size 1.27 1.27)
				)
				(justify mirror)
			)
		)
		(duplicate_pad_numbers_are_jumpers no)
		(fp_line
			(start -0.7874 -0.4064)
			(end -0.7874 0.4064)
			(stroke
				(width 0.1524)
				(type default)
			)
			(layer "B.SilkS")
		)
		(fp_line
			(start -0.7874 0.4064)
			(end 0.7874 0.4064)
			(stroke
				(width 0.1524)
				(type default)
			)
			(layer "B.SilkS")
		)
		(fp_line
			(start 0.7874 -0.4064)
			(end -0.7874 -0.4064)
			(stroke
				(width 0.1524)
				(type default)
			)
			(layer "B.SilkS")
		)
		(fp_line
			(start 0.7874 0.4064)
			(end 0.7874 -0.4064)
			(stroke
				(width 0.1524)
				(type default)
			)
			(layer "B.SilkS")
		)
		(fp_line
			(start -0.67945 -0.3048)
			(end -0.67945 0.3048)
			(stroke
				(width 0.1)
				(type default)
			)
			(layer "B.Fab")
		)
		(fp_line
			(start -0.67945 0.3048)
			(end -0.120396 0.3048)
			(stroke
				(width 0.1)
				(type default)
			)
			(layer "B.Fab")
		)
		(fp_line
			(start -0.12065 -0.3048)
			(end -0.67945 -0.3048)
			(stroke
				(width 0.1)
				(type default)
			)
			(layer "B.Fab")
		)
		(fp_line
			(start -0.12065 -0.2794)
			(end -0.12065 -0.3048)
			(stroke
				(width 0.1)
				(type default)
			)
			(layer "B.Fab")
		)
		(fp_line
			(start -0.120396 0.2794)
			(end 0.12065 0.2794)
			(stroke
				(width 0.1)
				(type default)
			)
			(layer "B.Fab")
		)
		(fp_line
			(start -0.120396 0.3048)
			(end -0.120396 0.2794)
			(stroke
				(width 0.1)
				(type default)
			)
			(layer "B.Fab")
		)
		(fp_line
			(start 0.12065 -0.305054)
			(end 0.12065 -0.2794)
			(stroke
				(width 0.1)
				(type default)
			)
			(layer "B.Fab")
		)
		(fp_line
			(start 0.12065 -0.2794)
			(end -0.12065 -0.2794)
			(stroke
				(width 0.1)
				(type default)
			)
			(layer "B.Fab")
		)
		(fp_line
			(start 0.12065 0.2794)
			(end 0.12065 0.3048)
			(stroke
				(width 0.1)
				(type default)
			)
			(layer "B.Fab")
		)
		(fp_line
			(start 0.12065 0.3048)
			(end 0.67945 0.3048)
			(stroke
				(width 0.1)
				(type default)
			)
			(layer "B.Fab")
		)
		(fp_line
			(start 0.67945 -0.305054)
			(end 0.12065 -0.305054)
			(stroke
				(width 0.1)
				(type default)
			)
			(layer "B.Fab")
		)
		(fp_line
			(start 0.67945 0.3048)
			(end 0.67945 -0.305054)
			(stroke
				(width 0.1)
				(type default)
			)
			(layer "B.Fab")
		)
		(pad "1" smd circle
			(at 0.40005 0 180)
			(size 0 0)
			(layers "B.Cu" "B.Mask" "B.Paste")
			(net "PVDDCR_CPU1_P1")
		)
		(pad "2" smd circle
			(at -0.40005 0 180)
			(size 0 0)
			(layers "B.Cu" "B.Mask" "B.Paste")
			(net "GND")
		)
	)
	(footprint ""
		(layer "B.Cu")
		(at 197.70725 -244.085364)
		(property "Reference" "R510"
			(at 0 0 0)
			(layer "B.SilkS")
			(hide yes)
			(effects
				(font
					(size 1.27 1.27)
				)
				(justify mirror)
			)
		)
		(property "Value" ""
			(at 0 0 0)
			(layer "B.Fab")
			(effects
				(font
					(size 1.27 1.27)
				)
				(justify mirror)
			)
		)
		(duplicate_pad_numbers_are_jumpers no)
		(fp_line
			(start -0.7874 -0.4064)
			(end -0.7874 0.4064)
			(stroke
				(width 0.1524)
				(type default)
			)
			(layer "B.SilkS")
		)
		(fp_line
			(start -0.7874 0.4064)
			(end 0.7874 0.4064)
			(stroke
				(width 0.1524)
				(type default)
			)
			(layer "B.SilkS")
		)
		(fp_line
			(start 0.7874 -0.4064)
			(end -0.7874 -0.4064)
			(stroke
				(width 0.1524)
				(type default)
			)
			(layer "B.SilkS")
		)
		(fp_line
			(start 0.7874 0.4064)
			(end 0.7874 -0.4064)
			(stroke
				(width 0.1524)
				(type default)
			)
			(layer "B.SilkS")
		)
		(fp_line
			(start -0.67945 -0.3048)
			(end -0.67945 0.3048)
			(stroke
				(width 0.1)
				(type default)
			)
			(layer "B.Fab")
		)
		(fp_line
			(start -0.67945 0.3048)
			(end -0.120396 0.3048)
			(stroke
				(width 0.1)
				(type default)
			)
			(layer "B.Fab")
		)
		(fp_line
			(start -0.12065 -0.3048)
			(end -0.67945 -0.3048)
			(stroke
				(width 0.1)
				(type default)
			)
			(layer "B.Fab")
		)
		(fp_line
			(start -0.12065 -0.2794)
			(end -0.12065 -0.3048)
			(stroke
				(width 0.1)
				(type default)
			)
			(layer "B.Fab")
		)
		(fp_line
			(start -0.120396 0.2794)
			(end 0.12065 0.2794)
			(stroke
				(width 0.1)
				(type default)
			)
			(layer "B.Fab")
		)
		(fp_line
			(start -0.120396 0.3048)
			(end -0.120396 0.2794)
			(stroke
				(width 0.1)
				(type default)
			)
			(layer "B.Fab")
		)
		(fp_line
			(start 0.12065 -0.305054)
			(end 0.12065 -0.2794)
			(stroke
				(width 0.1)
				(type default)
			)
			(layer "B.Fab")
		)
		(fp_line
			(start 0.12065 -0.2794)
			(end -0.12065 -0.2794)
			(stroke
				(width 0.1)
				(type default)
			)
			(layer "B.Fab")
		)
		(fp_line
			(start 0.12065 0.2794)
			(end 0.12065 0.3048)
			(stroke
				(width 0.1)
				(type default)
			)
			(layer "B.Fab")
		)
		(fp_line
			(start 0.12065 0.3048)
			(end 0.67945 0.3048)
			(stroke
				(width 0.1)
				(type default)
			)
			(layer "B.Fab")
		)
		(fp_line
			(start 0.67945 -0.305054)
			(end 0.12065 -0.305054)
			(stroke
				(width 0.1)
				(type default)
			)
			(layer "B.Fab")
		)
		(fp_line
			(start 0.67945 0.3048)
			(end 0.67945 -0.305054)
			(stroke
				(width 0.1)
				(type default)
			)
			(layer "B.Fab")
		)
		(pad "1" smd circle
			(at 0.40005 0 180)
			(size 0 0)
			(layers "B.Cu" "B.Mask" "B.Paste")
			(net "M_K_CPU1_ALERT_N")
		)
		(pad "2" smd circle
			(at -0.40005 0 180)
			(size 0 0)
			(layers "B.Cu" "B.Mask" "B.Paste")
			(net "M_K_CPU1_ALERT_R_N")
		)
	)
)
